# BASEBOARD_FAB2 (Tioga Pass) — schematic netlist excerpt (pin names and nets, part order shuffled) for the footprints in the layout excerpt that follows; sources: Cadence DE-HDL packaged netlist, KiCad conversion of Wiwynn_Tioga_Pass_MB.brd

J4A2  SCONN288_H44441004  SCONN  pkg PIP  page 51
  \12v\(1)  = P12V_NVDIMM_DEF
  VSS(93)  = GND
  DQ(4)  = M_E_DQ<5>
  VSS(92)  = GND
  DQ(0)  = M_E_DQ<1>
  VSS(91)  = GND
  DQS9P  = M_E_DQS_DP<9>
  DQS9N  = M_E_DQS_DN<9>
  VSS(90)  = GND
  DQ(6)  = M_E_DQ<7>
  VSS(89)  = GND
  DQ(2)  = M_E_DQ<3>
  VSS(88)  = GND
  DQ(12)  = M_E_DQ<13>
  VSS(87)  = GND
  DQ(8)  = M_E_DQ<9>
  VSS(86)  = GND
  DQS10P  = M_E_DQS_DP<10>
  DQS10N  = M_E_DQS_DN<10>
  VSS(85)  = GND
  DQ(14)  = M_E_DQ<15>
  VSS(84)  = GND
  DQ(10)  = M_E_DQ<11>
  VSS(83)  = GND
  DQ(20)  = M_E_DQ<21>
  VSS(82)  = GND
  DQ(16)  = M_E_DQ<17>
  VSS(81)  = GND
  DQS11P  = M_E_DQS_DP<11>
  DQS11N  = M_E_DQS_DN<11>
  VSS(80)  = GND
  DQ(22)  = M_E_DQ<23>
  VSS(79)  = GND
  DQ(18)  = M_E_DQ<19>
  VSS(78)  = GND
  DQ(28)  = M_E_DQ<29>
  VSS(77)  = GND
  DQ(24)  = M_E_DQ<25>
  VSS(76)  = GND
  DQS12P  = M_E_DQS_DP<12>
  DQS12N  = M_E_DQS_DN<12>
  VSS(75)  = GND
  DQ(30)  = M_E_DQ<31>
  VSS(74)  = GND
  DQ(26)  = M_E_DQ<27>
  VSS(73)  = GND
  CB(4)  = M_E_ECC<5>
  VSS(72)  = GND
  CB(0)  = M_E_ECC<1>
  VSS(71)  = GND
  DQS17P  = M_E_DQS_DP<17>
  DQS17N  = M_E_DQS_DN<17>
  VSS(70)  = GND
  CB(6)  = M_E_ECC<7>
  VSS(69)  = GND
  CB(2)  = M_E_ECC<3>
  VSS(68)  = GND
  RESET_N  = M_DEF_RST_N
  VDD(25)  = PVDDQ_DEF
  CKE(0)  = M_E_CKE<0>
  VDD(24)  = PVDDQ_DEF
  ACT_N  = M_E_ACT_N
  BG(0)  = M_E_BG<0>
  VDD(23)  = PVDDQ_DEF
  A12  = M_E_MA<12>
  A9  = M_E_MA<9>
  VDD(22)  = PVDDQ_DEF
  A8  = M_E_MA<8>
  A6  = M_E_MA<6>
  VDD(21)  = PVDDQ_DEF
  A3  = M_E_MA<3>
  A1  = M_E_MA<1>
  VDD(20)  = PVDDQ_DEF
  CK0P  = M_E_CLK_DP<0>
  CK0N  = M_E_CLK_DN<0>
  VDD(19)  = PVDDQ_DEF
  VTT(1)  = PVTT_DEF
  EVENT_N  = FM_DIMM_EVENT_COD_N
  A0  = M_E_MA<0>
  VDD(18)  = PVDDQ_DEF
  BA(0)  = M_E_BA<0>
  A16_RAS_N  = M_E_MA<16>
  VDD(17)  = PVDDQ_DEF
  S0_N  = M_E_CS_N<0>
  VDD(16)  = PVDDQ_DEF
  A15_CAS_N  = M_E_MA<15>
  ODT(0)  = M_E_ODT<0>
  VDD(15)  = PVDDQ_DEF
  S1_N  = M_E_CS_N<1>
  VDD(14)  = PVDDQ_DEF
  ODT(1)  = M_E_ODT<1>
  VDD(13)  = PVDDQ_DEF
  S2_N_C(0)  = M_E_CS_N<2>
  VSS(67)  = GND
  DQ(36)  = M_E_DQ<37>
  VSS(66)  = GND
  DQ(32)  = M_E_DQ<33>
  VSS(65)  = GND
  DQS13P  = M_E_DQS_DP<13>
  DQS13N  = M_E_DQS_DN<13>
  VSS(64)  = GND
  DQ(38)  = M_E_DQ<39>
  VSS(63)  = GND
  DQ(34)  = M_E_DQ<35>
  VSS(62)  = GND
  DQ(44)  = M_E_DQ<45>
  VSS(61)  = GND
  DQ(40)  = M_E_DQ<41>
  VSS(60)  = GND
  DQS14P  = M_E_DQS_DP<14>
  DQS14N  = M_E_DQS_DN<14>
  VSS(59)  = GND
  DQ(46)  = M_E_DQ<47>
  VSS(58)  = GND
  DQ(42)  = M_E_DQ<43>
  VSS(57)  = GND
  DQ(52)  = M_E_DQ<53>
  VSS(56)  = GND
  DQ(48)  = M_E_DQ<49>
  VSS(55)  = GND
  DQS15P  = M_E_DQS_DP<15>
  DQS15N  = M_E_DQS_DN<15>
  VSS(54)  = GND
  DQ(54)  = M_E_DQ<55>
  VSS(53)  = GND
  DQ(50)  = M_E_DQ<51>
  VSS(52)  = GND
  DQ(60)  = M_E_DQ<61>
  VSS(51)  = GND
  DQ(56)  = M_E_DQ<57>
  VSS(50)  = GND
  DQS16P  = M_E_DQS_DP<16>
  DQS16N  = M_E_DQS_DN<16>
  VSS(49)  = GND
  DQ(62)  = M_E_DQ<63>
  VSS(48)  = GND
  DQ(58)  = M_E_DQ<59>
  VSS(47)  = GND
  SA(0)  = GND
  SA(1)  = PVPP_DEF
  SCL  = SMB_DDR_DEF_VPP_SCL
  VPP(4)  = PVPP_DEF
  VPP(3)  = PVPP_DEF
  RFU(2)  = TP_CH_E_DIMM_E0_RFU_2
  \12v\(0)  = P12V_NVDIMM_DEF
  VREFCA  = M_E_VREF
  VSS(46)  = GND
  DQ(5)  = M_E_DQ<4>
  VSS(45)  = GND
  DQ(1)  = M_E_DQ<0>
  VSS(44)  = GND
  DQS0N  = M_E_DQS_DN<0>
  DQS0P  = M_E_DQS_DP<0>
  VSS(43)  = GND
  DQ(7)  = M_E_DQ<6>
  VSS(42)  = GND
  DQ(3)  = M_E_DQ<2>
  VSS(41)  = GND
  DQ(13)  = M_E_DQ<12>
  VSS(40)  = GND
  DQ(9)  = M_E_DQ<8>
  VSS(39)  = GND
  DQS1N  = M_E_DQS_DN<1>
  DQS1P  = M_E_DQS_DP<1>
  VSS(38)  = GND
  DQ(15)  = M_E_DQ<14>
  VSS(37)  = GND
  DQ(11)  = M_E_DQ<10>
  VSS(36)  = GND
  DQ(21)  = M_E_DQ<20>
  VSS(35)  = GND
  DQ(17)  = M_E_DQ<16>
  VSS(34)  = GND
  DQS2N  = M_E_DQS_DN<2>
  DQS2P  = M_E_DQS_DP<2>
  VSS(33)  = GND
  DQ(23)  = M_E_DQ<22>
  VSS(32)  = GND
  DQ(19)  = M_E_DQ<18>
  VSS(31)  = GND
  DQ(29)  = M_E_DQ<28>
  VSS(30)  = GND
  DQ(25)  = M_E_DQ<24>
  VSS(29)  = GND
  DQS3N  = M_E_DQS_DN<3>
  DQS3P  = M_E_DQS_DP<3>
  VSS(28)  = GND
  DQ(31)  = M_E_DQ<30>
  VSS(27)  = GND
  DQ(27)  = M_E_DQ<26>
  VSS(26)  = GND
  CB(5)  = M_E_ECC<4>
  VSS(25)  = GND
  CB(1)  = M_E_ECC<0>
  VSS(24)  = GND
  DQS8N  = M_E_DQS_DN<8>
  DQS8P  = M_E_DQS_DP<8>
  VSS(23)  = GND
  CB(7)  = M_E_ECC<6>
  VSS(22)  = GND
  CB(3)  = M_E_ECC<2>
  VSS(21)  = GND
  CKE(1)  = M_E_CKE<1>
  VDD(12)  = PVDDQ_DEF
  RFU(0)  = TP_CH_E_DIMM_E0_RFU_0
  VDD(11)  = PVDDQ_DEF
  BG(1)  = M_E_BG<1>
  ALERT_N  = M_E_ALERT_N
  VDD(10)  = PVDDQ_DEF
  A11  = M_E_MA<11>
  A7  = M_E_MA<7>
  VDD(9)  = PVDDQ_DEF
  A5  = M_E_MA<5>
  A4  = M_E_MA<4>
  VDD(8)  = PVDDQ_DEF
  A2  = M_E_MA<2>
  VDD(7)  = PVDDQ_DEF
  CK1P  = M_E_CLK_DP<1>
  CK1N  = M_E_CLK_DN<1>
  VDD(6)  = PVDDQ_DEF
  VTT(0)  = PVTT_DEF
  PAR  = M_E_PAR
  VDD(5)  = PVDDQ_DEF
  BA(1)  = M_E_BA<1>
  A10  = M_E_MA<10>
  VDD(4)  = PVDDQ_DEF
  RFU(1)  = TP_CH_E_DIMM_E0_RFU_1
  A14_WE_N  = M_E_MA<14>
  VDD(3)  = PVDDQ_DEF
  SAVE_N_NC  = FM_ADR_COMPLETE_DEF_N
  VDD(2)  = PVDDQ_DEF
  A13  = M_E_MA<13>
  VDD(1)  = PVDDQ_DEF
  A17  = M_E_MA<17>
  C(2)  = M_E_C<2>
  VDD(0)  = PVDDQ_DEF
  S3_N_C(1)  = M_E_CS_N<3>
  SA(2)  = GND
  VSS(20)  = GND
  DQ(37)  = M_E_DQ<36>
  VSS(19)  = GND
  DQ(33)  = M_E_DQ<32>
  VSS(18)  = GND
  DQS4N  = M_E_DQS_DN<4>
  DQS4P  = M_E_DQS_DP<4>
  VSS(17)  = GND
  DQ(39)  = M_E_DQ<38>
  VSS(16)  = GND
  DQ(35)  = M_E_DQ<34>
  VSS(15)  = GND
  DQ(45)  = M_E_DQ<44>
  VSS(14)  = GND
  DQ(41)  = M_E_DQ<40>
  VSS(13)  = GND
  DQS5N  = M_E_DQS_DN<5>
  DQS5P  = M_E_DQS_DP<5>
  VSS(12)  = GND
  DQ(47)  = M_E_DQ<46>
  VSS(11)  = GND
  DQ(43)  = M_E_DQ<42>
  VSS(10)  = GND
  DQ(53)  = M_E_DQ<52>
  VSS(9)  = GND
  DQ(49)  = M_E_DQ<48>
  VSS(8)  = GND
  DQS6N  = M_E_DQS_DN<6>
  DQS6P  = M_E_DQS_DP<6>
  VSS(7)  = GND
  DQ(55)  = M_E_DQ<54>
  VSS(6)  = GND
  DQ(51)  = M_E_DQ<50>
  VSS(5)  = GND
  DQ(61)  = M_E_DQ<60>
  VSS(4)  = GND
  DQ(57)  = M_E_DQ<56>
  VSS(3)  = GND
  DQS7N  = M_E_DQS_DN<7>
  DQS7P  = M_E_DQS_DP<7>
  VSS(2)  = GND
  DQ(63)  = M_E_DQ<62>
  VSS(1)  = GND
  DQ(59)  = M_E_DQ<58>
  VSS(0)  = GND
  VDDSPD  = PVPP_DEF
  SDA  = SMB_DDR_DEF_VPP_SDA
  VPP(1)  = PVPP_DEF
  VPP(0)  = PVPP_DEF
  VPP(2)  = PVPP_DEF

(kicad_pcb
	(version 20260206)
	(generator "pcbnew")
	(generator_version "10.0")
	(general
		(thickness 1.6)
		(legacy_teardrops no)
	)
	(paper "A4")
	(title_block
		(title "Wiwynn_Tioga_Pass_MB.brd")
		(comment 1 "Tioga Pass / footprint 2096 of 4770 (J4A2), pads 203-251 of 291")
	)
	(layers
		(0 "F.Cu" signal "TOP")
		(4 "In1.Cu" signal "L2GND")
		(6 "In2.Cu" signal "L3")
		(8 "In3.Cu" signal "L4GND")
		(10 "In4.Cu" signal "L5")
		(12 "In5.Cu" signal "L6GND")
		(14 "In6.Cu" signal "L7VCC")
		(16 "In7.Cu" signal "L8VCC")
		(18 "In8.Cu" signal "L9GND")
		(20 "In9.Cu" signal "L10")
		(22 "In10.Cu" signal "L11GND")
		(24 "In11.Cu" signal "L12")
		(26 "In12.Cu" signal "L13GND")
		(2 "B.Cu" signal "BOTTOM")
		(9 "F.Adhes" user "F.Adhesive")
		(11 "B.Adhes" user "B.Adhesive")
		(13 "F.Paste" user "Package Geometry/Pastemask Top")
		(15 "B.Paste" user "Package Geometry/Pastemask Bottom")
		(5 "F.SilkS" user "Ref Des/Silkscreen Top")
		(7 "B.SilkS" user "Ref Des/Silkscreen Bottom")
		(1 "F.Mask" user "Board Geometry/Soldermask Top")
		(3 "B.Mask" user "Board Geometry/Soldermask Bottom")
		(17 "Dwgs.User" user "User.Drawings")
		(19 "Cmts.User" user "User.Comments")
		(21 "Eco1.User" user "User.Eco1")
		(23 "Eco2.User" user "User.Eco2")
		(25 "Edge.Cuts" user "Board Geometry/Outline")
		(27 "Margin" user)
		(31 "F.CrtYd" user "Package Geometry/Place Bound Top")
		(29 "B.CrtYd" user "Package Geometry/Place Bound Bottom")
		(35 "F.Fab" user "Ref Des/Assembly Top")
		(33 "B.Fab" user "Ref Des/Assembly Bottom")
	)
	(footprint ""
		(layer "F.Cu")
		(at 194.700398 -142.6718 90)
		(property "Reference" "J4A2"
			(at -2.369312 42.66311 0)
			(unlocked yes)
			(layer "F.SilkS")
			(effects
				(font
					(size 0.7874 0.5842)
					(thickness 0.1524)
				)
				(justify left)
			)
		)
		(property "Value" ""
			(at 0 0 90)
			(layer "F.Fab")
			(effects
				(font
					(size 1.27 1.27)
				)
			)
		)
		(duplicate_pad_numbers_are_jumpers no)
		(pad "200" smd rect
			(at 4.59994 46.74997 90)
			(size 1.8034 0.508)
			(layers "F.Cu" "F.Mask" "F.Paste")
			(net "GND")
		)
		(pad "201" smd rect
			(at 4.59994 47.600108 90)
			(size 1.8034 0.508)
			(layers "F.Cu" "F.Mask" "F.Paste")
			(net "M_E_ECC<2>")
		)
		(pad "202" smd rect
			(at 4.59994 48.449992 90)
			(size 1.8034 0.508)
			(layers "F.Cu" "F.Mask" "F.Paste")
			(net "GND")
		)
		(pad "203" smd rect
			(at 4.59994 49.299876 90)
			(size 1.8034 0.508)
			(layers "F.Cu" "F.Mask" "F.Paste")
			(net "M_E_CKE<1>")
		)
		(pad "204" smd rect
			(at 4.59994 50.150014 90)
			(size 1.8034 0.508)
			(layers "F.Cu" "F.Mask" "F.Paste")
			(net "PVDDQ_DEF")
		)
		(pad "205" smd rect
			(at 4.59994 50.999898 90)
			(size 1.8034 0.508)
			(layers "F.Cu" "F.Mask" "F.Paste")
			(net "TP_CH_E_DIMM_E0_RFU_0")
		)
		(pad "206" smd rect
			(at 4.59994 51.850036 90)
			(size 1.8034 0.508)
			(layers "F.Cu" "F.Mask" "F.Paste")
			(net "PVDDQ_DEF")
		)
		(pad "207" smd rect
			(at 4.59994 52.69992 90)
			(size 1.8034 0.508)
			(layers "F.Cu" "F.Mask" "F.Paste")
			(net "M_E_BG<1>")
		)
		(pad "208" smd rect
			(at 4.59994 53.550058 90)
			(size 1.8034 0.508)
			(layers "F.Cu" "F.Mask" "F.Paste")
			(net "M_E_ALERT_N")
		)
		(pad "209" smd rect
			(at 4.59994 54.399942 90)
			(size 1.8034 0.508)
			(layers "F.Cu" "F.Mask" "F.Paste")
			(net "PVDDQ_DEF")
		)
		(pad "210" smd rect
			(at 4.59994 55.25008 90)
			(size 1.8034 0.508)
			(layers "F.Cu" "F.Mask" "F.Paste")
			(net "M_E_MA<11>")
		)
		(pad "211" smd rect
			(at 4.59994 56.099964 90)
			(size 1.8034 0.508)
			(layers "F.Cu" "F.Mask" "F.Paste")
			(net "M_E_MA<7>")
		)
		(pad "212" smd rect
			(at 4.59994 56.950102 90)
			(size 1.8034 0.508)
			(layers "F.Cu" "F.Mask" "F.Paste")
			(net "PVDDQ_DEF")
		)
		(pad "213" smd rect
			(at 4.59994 57.799986 90)
			(size 1.8034 0.508)
			(layers "F.Cu" "F.Mask" "F.Paste")
			(net "M_E_MA<5>")
		)
		(pad "214" smd rect
			(at 4.59994 58.650124 90)
			(size 1.8034 0.508)
			(layers "F.Cu" "F.Mask" "F.Paste")
			(net "M_E_MA<4>")
		)
		(pad "215" smd rect
			(at 4.59994 59.500008 90)
			(size 1.8034 0.508)
			(layers "F.Cu" "F.Mask" "F.Paste")
			(net "PVDDQ_DEF")
		)
		(pad "216" smd rect
			(at 4.59994 60.349892 90)
			(size 1.8034 0.508)
			(layers "F.Cu" "F.Mask" "F.Paste")
			(net "M_E_MA<2>")
		)
		(pad "217" smd rect
			(at 4.59994 61.20003 90)
			(size 1.8034 0.508)
			(layers "F.Cu" "F.Mask" "F.Paste")
			(net "PVDDQ_DEF")
		)
		(pad "218" smd rect
			(at 4.59994 62.049914 90)
			(size 1.8034 0.508)
			(layers "F.Cu" "F.Mask" "F.Paste")
			(net "M_E_CLK_DP<1>")
		)
		(pad "219" smd rect
			(at 4.59994 62.900052 90)
			(size 1.8034 0.508)
			(layers "F.Cu" "F.Mask" "F.Paste")
			(net "M_E_CLK_DN<1>")
		)
		(pad "220" smd rect
			(at 4.59994 63.749936 90)
			(size 1.8034 0.508)
			(layers "F.Cu" "F.Mask" "F.Paste")
			(net "PVDDQ_DEF")
		)
		(pad "221" smd rect
			(at 4.59994 64.600074 90)
			(size 1.8034 0.508)
			(layers "F.Cu" "F.Mask" "F.Paste")
			(net "PVTT_DEF")
		)
		(pad "222" smd rect
			(at 4.59994 70.550024 90)
			(size 1.8034 0.508)
			(layers "F.Cu" "F.Mask" "F.Paste")
			(net "M_E_PAR")
		)
		(pad "223" smd rect
			(at 4.59994 71.399908 90)
			(size 1.8034 0.508)
			(layers "F.Cu" "F.Mask" "F.Paste")
			(net "PVDDQ_DEF")
		)
		(pad "224" smd rect
			(at 4.59994 72.250046 90)
			(size 1.8034 0.508)
			(layers "F.Cu" "F.Mask" "F.Paste")
			(net "M_E_BA<1>")
		)
		(pad "225" smd rect
			(at 4.59994 73.09993 90)
			(size 1.8034 0.508)
			(layers "F.Cu" "F.Mask" "F.Paste")
			(net "M_E_MA<10>")
		)
		(pad "226" smd rect
			(at 4.59994 73.950068 90)
			(size 1.8034 0.508)
			(layers "F.Cu" "F.Mask" "F.Paste")
			(net "PVDDQ_DEF")
		)
		(pad "227" smd rect
			(at 4.59994 74.799952 90)
			(size 1.8034 0.508)
			(layers "F.Cu" "F.Mask" "F.Paste")
			(net "TP_CH_E_DIMM_E0_RFU_1")
		)
		(pad "228" smd rect
			(at 4.59994 75.65009 90)
			(size 1.8034 0.508)
			(layers "F.Cu" "F.Mask" "F.Paste")
			(net "M_E_MA<14>")
		)
		(pad "229" smd rect
			(at 4.59994 76.499974 90)
			(size 1.8034 0.508)
			(layers "F.Cu" "F.Mask" "F.Paste")
			(net "PVDDQ_DEF")
		)
		(pad "230" smd rect
			(at 4.59994 77.350112 90)
			(size 1.8034 0.508)
			(layers "F.Cu" "F.Mask" "F.Paste")
			(net "FM_ADR_COMPLETE_DEF_N")
		)
		(pad "231" smd rect
			(at 4.59994 78.199996 90)
			(size 1.8034 0.508)
			(layers "F.Cu" "F.Mask" "F.Paste")
			(net "PVDDQ_DEF")
		)
		(pad "232" smd rect
			(at 4.59994 79.04988 90)
			(size 1.8034 0.508)
			(layers "F.Cu" "F.Mask" "F.Paste")
			(net "M_E_MA<13>")
		)
		(pad "233" smd rect
			(at 4.59994 79.900018 90)
			(size 1.8034 0.508)
			(layers "F.Cu" "F.Mask" "F.Paste")
			(net "PVDDQ_DEF")
		)
		(pad "234" smd rect
			(at 4.59994 80.749902 90)
			(size 1.8034 0.508)
			(layers "F.Cu" "F.Mask" "F.Paste")
			(net "M_E_MA<17>")
		)
		(pad "235" smd rect
			(at 4.59994 81.60004 90)
			(size 1.8034 0.508)
			(layers "F.Cu" "F.Mask" "F.Paste")
			(net "M_E_C<2>")
		)
		(pad "236" smd rect
			(at 4.59994 82.449924 90)
			(size 1.8034 0.508)
			(layers "F.Cu" "F.Mask" "F.Paste")
			(net "PVDDQ_DEF")
		)
		(pad "237" smd rect
			(at 4.59994 83.300062 90)
			(size 1.8034 0.508)
			(layers "F.Cu" "F.Mask" "F.Paste")
			(net "M_E_CS_N<3>")
		)
		(pad "238" smd rect
			(at 4.59994 84.149946 90)
			(size 1.8034 0.508)
			(layers "F.Cu" "F.Mask" "F.Paste")
			(net "GND")
		)
		(pad "239" smd rect
			(at 4.59994 85.000084 90)
			(size 1.8034 0.508)
			(layers "F.Cu" "F.Mask" "F.Paste")
			(net "GND")
		)
		(pad "240" smd rect
			(at 4.59994 85.849968 90)
			(size 1.8034 0.508)
			(layers "F.Cu" "F.Mask" "F.Paste")
			(net "M_E_DQ<36>")
		)
		(pad "241" smd rect
			(at 4.59994 86.700106 90)
			(size 1.8034 0.508)
			(layers "F.Cu" "F.Mask" "F.Paste")
			(net "GND")
		)
		(pad "242" smd rect
			(at 4.59994 87.54999 90)
			(size 1.8034 0.508)
			(layers "F.Cu" "F.Mask" "F.Paste")
			(net "M_E_DQ<32>")
		)
		(pad "243" smd rect
			(at 4.59994 88.399874 90)
			(size 1.8034 0.508)
			(layers "F.Cu" "F.Mask" "F.Paste")
			(net "GND")
		)
		(pad "244" smd rect
			(at 4.59994 89.250012 90)
			(size 1.8034 0.508)
			(layers "F.Cu" "F.Mask" "F.Paste")
			(net "M_E_DQS_DN<4>")
		)
		(pad "245" smd rect
			(at 4.59994 90.099896 90)
			(size 1.8034 0.508)
			(layers "F.Cu" "F.Mask" "F.Paste")
			(net "M_E_DQS_DP<4>")
		)
		(pad "246" smd rect
			(at 4.59994 90.950034 90)
			(size 1.8034 0.508)
			(layers "F.Cu" "F.Mask" "F.Paste")
			(net "GND")
		)
		(pad "247" smd rect
			(at 4.59994 91.799918 90)
			(size 1.8034 0.508)
			(layers "F.Cu" "F.Mask" "F.Paste")
			(net "M_E_DQ<38>")
		)
		(pad "248" smd rect
			(at 4.59994 92.650056 90)
			(size 1.8034 0.508)
			(layers "F.Cu" "F.Mask" "F.Paste")
			(net "GND")
		)
	)
)
